# S9S_MB_2U (Grand Teton) — schematic netlist excerpt (pin names and nets, part order shuffled) for the footprints in the layout excerpt that follows; sources: Cadence DE-HDL packaged netlist, KiCad conversion of 03242023_DA0F0TMBIJ0_F0T_Motherboard_J_brd_V01_OCP.brd

R10  Q_RES  33.2 1% CHIP  pkg 0402LF  page 14 : A = H_CPU0_PMSYNC_PCH_R ; B = H_CPU0_PMSYNC_PCH
C2258  Q_CAP  0.1UF 25V 10% X7R  pkg 0402  page 212 : A = VFG3P3_CLK_GEN ; B = GND

(kicad_pcb
	(version 20260206)
	(generator "pcbnew")
	(generator_version "10.0")
	(general
		(thickness 1.6)
		(legacy_teardrops no)
	)
	(paper "A4")
	(title_block
		(title "03242023_DA0F0TMBIJ0_F0T_Motherboard_J_brd_V01_OCP.brd")
		(comment 1 "Grand Teton / footprints 5504-5505 of 6105")
	)
	(layers
		(0 "F.Cu" signal "TOP")
		(4 "In1.Cu" signal "GND")
		(6 "In2.Cu" signal "IN1")
		(8 "In3.Cu" signal "GND1")
		(10 "In4.Cu" signal "IN2")
		(12 "In5.Cu" signal "GND2")
		(14 "In6.Cu" signal "IN3")
		(16 "In7.Cu" signal "GND3")
		(18 "In8.Cu" signal "VCC")
		(20 "In9.Cu" signal "VCC1")
		(22 "In10.Cu" signal "GND4")
		(24 "In11.Cu" signal "IN4")
		(26 "In12.Cu" signal "GND5")
		(28 "In13.Cu" signal "IN5")
		(30 "In14.Cu" signal "GND6")
		(32 "In15.Cu" signal "IN6")
		(34 "In16.Cu" signal "GND7")
		(2 "B.Cu" signal "BOTTOM")
		(9 "F.Adhes" user "F.Adhesive")
		(11 "B.Adhes" user "B.Adhesive")
		(13 "F.Paste" user "Package Geometry/Pastemask Top")
		(15 "B.Paste" user "Package Geometry/Pastemask Bottom")
		(5 "F.SilkS" user "Ref Des/Silkscreen Top")
		(7 "B.SilkS" user "Ref Des/Silkscreen Bottom")
		(1 "F.Mask" user "Board Geometry/Soldermask Top")
		(3 "B.Mask" user "Board Geometry/Soldermask Bottom")
		(17 "Dwgs.User" user "User.Drawings")
		(19 "Cmts.User" user "User.Comments")
		(21 "Eco1.User" user "User.Eco1")
		(23 "Eco2.User" user "User.Eco2")
		(25 "Edge.Cuts" user "Board Geometry/Outline")
		(27 "Margin" user)
		(31 "F.CrtYd" user "Package Geometry/Place Bound Top")
		(29 "B.CrtYd" user "Package Geometry/Place Bound Bottom")
		(35 "F.Fab" user "Ref Des/Assembly Top")
		(33 "B.Fab" user "Ref Des/Assembly Bottom")
	)
	(footprint ""
		(layer "B.Cu")
		(at 401.832318 -229.12451 -90)
		(property "Reference" "R10"
			(at 0 0 90)
			(layer "B.SilkS")
			(hide yes)
			(effects
				(font
					(size 1.27 1.27)
				)
				(justify mirror)
			)
		)
		(property "Value" ""
			(at 0 0 90)
			(layer "B.Fab")
			(effects
				(font
					(size 1.27 1.27)
				)
				(justify mirror)
			)
		)
		(duplicate_pad_numbers_are_jumpers no)
		(fp_line
			(start -0.7874 0.4064)
			(end 0.7874 0.4064)
			(stroke
				(width 0.1524)
				(type default)
			)
			(layer "B.SilkS")
		)
		(fp_line
			(start 0.7874 0.4064)
			(end 0.7874 -0.4064)
			(stroke
				(width 0.1524)
				(type default)
			)
			(layer "B.SilkS")
		)
		(fp_line
			(start -0.7874 -0.4064)
			(end -0.7874 0.4064)
			(stroke
				(width 0.1524)
				(type default)
			)
			(layer "B.SilkS")
		)
		(fp_line
			(start 0.7874 -0.4064)
			(end -0.7874 -0.4064)
			(stroke
				(width 0.1524)
				(type default)
			)
			(layer "B.SilkS")
		)
		(fp_line
			(start -0.67945 0.3048)
			(end -0.120396 0.3048)
			(stroke
				(width 0.1)
				(type default)
			)
			(layer "B.Fab")
		)
		(fp_line
			(start -0.120396 0.3048)
			(end -0.120396 0.2794)
			(stroke
				(width 0.1)
				(type default)
			)
			(layer "B.Fab")
		)
		(fp_line
			(start 0.12065 0.3048)
			(end 0.67945 0.3048)
			(stroke
				(width 0.1)
				(type default)
			)
			(layer "B.Fab")
		)
		(fp_line
			(start 0.67945 0.3048)
			(end 0.67945 -0.305054)
			(stroke
				(width 0.1)
				(type default)
			)
			(layer "B.Fab")
		)
		(fp_line
			(start -0.120396 0.2794)
			(end 0.12065 0.2794)
			(stroke
				(width 0.1)
				(type default)
			)
			(layer "B.Fab")
		)
		(fp_line
			(start 0.12065 0.2794)
			(end 0.12065 0.3048)
			(stroke
				(width 0.1)
				(type default)
			)
			(layer "B.Fab")
		)
		(fp_line
			(start -0.12065 -0.2794)
			(end -0.12065 -0.3048)
			(stroke
				(width 0.1)
				(type default)
			)
			(layer "B.Fab")
		)
		(fp_line
			(start 0.12065 -0.2794)
			(end -0.12065 -0.2794)
			(stroke
				(width 0.1)
				(type default)
			)
			(layer "B.Fab")
		)
		(fp_line
			(start -0.67945 -0.3048)
			(end -0.67945 0.3048)
			(stroke
				(width 0.1)
				(type default)
			)
			(layer "B.Fab")
		)
		(fp_line
			(start -0.12065 -0.3048)
			(end -0.67945 -0.3048)
			(stroke
				(width 0.1)
				(type default)
			)
			(layer "B.Fab")
		)
		(fp_line
			(start 0.12065 -0.305054)
			(end 0.12065 -0.2794)
			(stroke
				(width 0.1)
				(type default)
			)
			(layer "B.Fab")
		)
		(fp_line
			(start 0.67945 -0.305054)
			(end 0.12065 -0.305054)
			(stroke
				(width 0.1)
				(type default)
			)
			(layer "B.Fab")
		)
		(pad "1" smd circle
			(at 0.40005 0 90)
			(size 0 0)
			(layers "B.Cu" "B.Mask" "B.Paste")
			(net "H_CPU0_PMSYNC_PCH_R")
		)
		(pad "2" smd circle
			(at -0.40005 0 90)
			(size 0 0)
			(layers "B.Cu" "B.Mask" "B.Paste")
			(net "H_CPU0_PMSYNC_PCH")
		)
	)
	(footprint ""
		(layer "B.Cu")
		(at 235.30052 -249.220228 -90)
		(property "Reference" "C2258"
			(at 0 0 90)
			(layer "B.SilkS")
			(hide yes)
			(effects
				(font
					(size 1.27 1.27)
				)
				(justify mirror)
			)
		)
		(property "Value" ""
			(at 0 0 90)
			(layer "B.Fab")
			(effects
				(font
					(size 1.27 1.27)
				)
				(justify mirror)
			)
		)
		(duplicate_pad_numbers_are_jumpers no)
		(fp_line
			(start -0.7874 0.4064)
			(end 0.7874 0.4064)
			(stroke
				(width 0.1524)
				(type default)
			)
			(layer "B.SilkS")
		)
		(fp_line
			(start 0.7874 0.4064)
			(end 0.7874 -0.4064)
			(stroke
				(width 0.1524)
				(type default)
			)
			(layer "B.SilkS")
		)
		(fp_line
			(start -0.7874 -0.4064)
			(end -0.7874 0.4064)
			(stroke
				(width 0.1524)
				(type default)
			)
			(layer "B.SilkS")
		)
		(fp_line
			(start 0.7874 -0.4064)
			(end -0.7874 -0.4064)
			(stroke
				(width 0.1524)
				(type default)
			)
			(layer "B.SilkS")
		)
		(fp_line
			(start -0.67945 0.3048)
			(end -0.120396 0.3048)
			(stroke
				(width 0.1)
				(type default)
			)
			(layer "B.Fab")
		)
		(fp_line
			(start -0.120396 0.3048)
			(end -0.120396 0.2794)
			(stroke
				(width 0.1)
				(type default)
			)
			(layer "B.Fab")
		)
		(fp_line
			(start 0.12065 0.3048)
			(end 0.67945 0.3048)
			(stroke
				(width 0.1)
				(type default)
			)
			(layer "B.Fab")
		)
		(fp_line
			(start 0.67945 0.3048)
			(end 0.67945 -0.305054)
			(stroke
				(width 0.1)
				(type default)
			)
			(layer "B.Fab")
		)
		(fp_line
			(start -0.120396 0.2794)
			(end 0.12065 0.2794)
			(stroke
				(width 0.1)
				(type default)
			)
			(layer "B.Fab")
		)
		(fp_line
			(start 0.12065 0.2794)
			(end 0.12065 0.3048)
			(stroke
				(width 0.1)
				(type default)
			)
			(layer "B.Fab")
		)
		(fp_line
			(start -0.12065 -0.2794)
			(end -0.12065 -0.3048)
			(stroke
				(width 0.1)
				(type default)
			)
			(layer "B.Fab")
		)
		(fp_line
			(start 0.12065 -0.2794)
			(end -0.12065 -0.2794)
			(stroke
				(width 0.1)
				(type default)
			)
			(layer "B.Fab")
		)
		(fp_line
			(start -0.67945 -0.3048)
			(end -0.67945 0.3048)
			(stroke
				(width 0.1)
				(type default)
			)
			(layer "B.Fab")
		)
		(fp_line
			(start -0.12065 -0.3048)
			(end -0.67945 -0.3048)
			(stroke
				(width 0.1)
				(type default)
			)
			(layer "B.Fab")
		)
		(fp_line
			(start 0.12065 -0.305054)
			(end 0.12065 -0.2794)
			(stroke
				(width 0.1)
				(type default)
			)
			(layer "B.Fab")
		)
		(fp_line
			(start 0.67945 -0.305054)
			(end 0.12065 -0.305054)
			(stroke
				(width 0.1)
				(type default)
			)
			(layer "B.Fab")
		)
		(pad "1" smd circle
			(at 0.40005 0 90)
			(size 0 0)
			(layers "B.Cu" "B.Mask" "B.Paste")
			(net "VFG3P3_CLK_GEN")
		)
		(pad "2" smd circle
			(at -0.40005 0 90)
			(size 0 0)
			(layers "B.Cu" "B.Mask" "B.Paste")
			(net "GND")
		)
	)
)
